(kicad_pcb
	(version 20260206)
	(generator "pcbnew")
	(generator_version "10.0")
	(general
		(thickness 1.6)
		(legacy_teardrops no)
	)
	(paper "A4")
	(title_block
		(title "03242023_DA0F0TMBIJ0_F0T_Motherboard_J_brd_V01_OCP.brd")
		(comment 1 "Grand Teton / footprints 675-682 of 6105")
	)
	(layers
		(0 "F.Cu" signal "TOP")
		(4 "In1.Cu" signal "GND")
		(6 "In2.Cu" signal "IN1")
		(8 "In3.Cu" signal "GND1")
		(10 "In4.Cu" signal "IN2")
		(12 "In5.Cu" signal "GND2")
		(14 "In6.Cu" signal "IN3")
		(16 "In7.Cu" signal "GND3")
		(18 "In8.Cu" signal "VCC")
		(20 "In9.Cu" signal "VCC1")
		(22 "In10.Cu" signal "GND4")
		(24 "In11.Cu" signal "IN4")
		(26 "In12.Cu" signal "GND5")
		(28 "In13.Cu" signal "IN5")
		(30 "In14.Cu" signal "GND6")
		(32 "In15.Cu" signal "IN6")
		(34 "In16.Cu" signal "GND7")
		(2 "B.Cu" signal "BOTTOM")
		(9 "F.Adhes" user "F.Adhesive")
		(11 "B.Adhes" user "B.Adhesive")
		(13 "F.Paste" user "Package Geometry/Pastemask Top")
		(15 "B.Paste" user "Package Geometry/Pastemask Bottom")
		(5 "F.SilkS" user "Ref Des/Silkscreen Top")
		(7 "B.SilkS" user "Ref Des/Silkscreen Bottom")
		(1 "F.Mask" user "Board Geometry/Soldermask Top")
		(3 "B.Mask" user "Board Geometry/Soldermask Bottom")
		(17 "Dwgs.User" user "User.Drawings")
		(19 "Cmts.User" user "User.Comments")
		(21 "Eco1.User" user "User.Eco1")
		(23 "Eco2.User" user "User.Eco2")
		(25 "Edge.Cuts" user "Board Geometry/Outline")
		(27 "Margin" user)
		(31 "F.CrtYd" user "Package Geometry/Place Bound Top")
		(29 "B.CrtYd" user "Package Geometry/Place Bound Bottom")
		(35 "F.Fab" user "Ref Des/Assembly Top")
		(33 "B.Fab" user "Ref Des/Assembly Bottom")
	)
	(footprint ""
		(layer "F.Cu")
		(at 351.6757 -64.440562)
		(property "Reference" "C143"
			(at 0 0 0)
			(layer "F.SilkS")
			(hide yes)
			(effects
				(font
					(size 1.27 1.27)
				)
			)
		)
		(property "Value" ""
			(at 0 0 0)
			(layer "F.Fab")
			(effects
				(font
					(size 1.27 1.27)
				)
			)
		)
		(duplicate_pad_numbers_are_jumpers no)
		(fp_line
			(start -0.299974 -0.150114)
			(end 0.299974 -0.150114)
			(stroke
				(width 0.1)
				(type default)
			)
			(layer "F.Fab")
		)
		(fp_line
			(start -0.299974 0.150114)
			(end -0.299974 -0.150114)
			(stroke
				(width 0.1)
				(type default)
			)
			(layer "F.Fab")
		)
		(fp_line
			(start 0.299974 -0.150114)
			(end 0.299974 0.150114)
			(stroke
				(width 0.1)
				(type default)
			)
			(layer "F.Fab")
		)
		(fp_line
			(start 0.299974 0.150114)
			(end -0.299974 0.150114)
			(stroke
				(width 0.1)
				(type default)
			)
			(layer "F.Fab")
		)
		(pad "1" smd rect
			(at -0.2667 0)
			(size 0.3048 0.381)
			(layers "F.Cu" "F.Mask" "F.Paste")
			(net "DMI_CPU0_PCH_TX_C_DN<5>")
		)
		(pad "2" smd rect
			(at 0.2667 0)
			(size 0.3048 0.381)
			(layers "F.Cu" "F.Mask" "F.Paste")
			(net "DMI_CPU0_PCH_TX_DN<5>")
		)
		(zone
			(layer "In1.Cu")
			(hatch none 0.5)
			(connect_pads
				(clearance 0)
			)
			(min_thickness 0.25)
			(keepout
				(tracks not_allowed)
				(vias allowed)
				(pads allowed)
				(copperpour not_allowed)
				(footprints allowed)
			)
			(placement
				(enabled no)
				(sheetname "")
			)
			(fill
				(thermal_gap 0.5)
				(thermal_bridge_width 0.5)
				(island_removal_mode 0)
			)
			(polygon
				(pts
					(arc
						(start 351.282 -64.199262)
						(mid 351.228118 -64.22158)
						(end 351.2058 -64.275462)
					)
					(arc
						(start 351.2058 -64.605662)
						(mid 351.228118 -64.659544)
						(end 351.282 -64.681862)
					)
					(arc
						(start 351.536 -64.681862)
						(mid 351.589882 -64.659544)
						(end 351.6122 -64.605662)
					)
					(arc
						(start 351.6122 -64.275462)
						(mid 351.589882 -64.22158)
						(end 351.536 -64.199262)
					)
				)
			)
		)
		(zone
			(layer "In1.Cu")
			(hatch none 0.5)
			(connect_pads
				(clearance 0)
			)
			(min_thickness 0.25)
			(keepout
				(tracks not_allowed)
				(vias allowed)
				(pads allowed)
				(copperpour not_allowed)
				(footprints allowed)
			)
			(placement
				(enabled no)
				(sheetname "")
			)
			(fill
				(thermal_gap 0.5)
				(thermal_bridge_width 0.5)
				(island_removal_mode 0)
			)
			(polygon
				(pts
					(arc
						(start 351.8154 -64.199262)
						(mid 351.761518 -64.22158)
						(end 351.7392 -64.275462)
					)
					(arc
						(start 351.7392 -64.605662)
						(mid 351.761518 -64.659544)
						(end 351.8154 -64.681862)
					)
					(arc
						(start 352.0694 -64.681862)
						(mid 352.123282 -64.659544)
						(end 352.1456 -64.605662)
					)
					(arc
						(start 352.1456 -64.275462)
						(mid 352.123282 -64.22158)
						(end 352.0694 -64.199262)
					)
				)
			)
		)
	)
	(footprint ""
		(layer "F.Cu")
		(at 420.682166 -137.178034 180)
		(property "Reference" "PC222"
			(at 0 0 180)
			(layer "F.SilkS")
			(hide yes)
			(effects
				(font
					(size 1.27 1.27)
				)
			)
		)
		(property "Value" ""
			(at 0 0 180)
			(layer "F.Fab")
			(effects
				(font
					(size 1.27 1.27)
				)
			)
		)
		(duplicate_pad_numbers_are_jumpers no)
		(fp_line
			(start 0.7874 0.4064)
			(end -0.7874 0.4064)
			(stroke
				(width 0.1524)
				(type default)
			)
			(layer "F.SilkS")
		)
		(fp_line
			(start 0.7874 -0.4064)
			(end 0.7874 0.4064)
			(stroke
				(width 0.1524)
				(type default)
			)
			(layer "F.SilkS")
		)
		(fp_line
			(start -0.7874 0.4064)
			(end -0.7874 -0.4064)
			(stroke
				(width 0.1524)
				(type default)
			)
			(layer "F.SilkS")
		)
		(fp_line
			(start -0.7874 -0.4064)
			(end 0.7874 -0.4064)
			(stroke
				(width 0.1524)
				(type default)
			)
			(layer "F.SilkS")
		)
		(fp_line
			(start 0.67945 0.3048)
			(end 0.120396 0.3048)
			(stroke
				(width 0.1)
				(type default)
			)
			(layer "F.Fab")
		)
		(fp_line
			(start 0.67945 -0.3048)
			(end 0.67945 0.3048)
			(stroke
				(width 0.1)
				(type default)
			)
			(layer "F.Fab")
		)
		(fp_line
			(start 0.12065 -0.2794)
			(end 0.12065 -0.3048)
			(stroke
				(width 0.1)
				(type default)
			)
			(layer "F.Fab")
		)
		(fp_line
			(start 0.12065 -0.3048)
			(end 0.67945 -0.3048)
			(stroke
				(width 0.1)
				(type default)
			)
			(layer "F.Fab")
		)
		(fp_line
			(start 0.120396 0.3048)
			(end 0.120396 0.2794)
			(stroke
				(width 0.1)
				(type default)
			)
			(layer "F.Fab")
		)
		(fp_line
			(start 0.120396 0.2794)
			(end -0.12065 0.2794)
			(stroke
				(width 0.1)
				(type default)
			)
			(layer "F.Fab")
		)
		(fp_line
			(start -0.12065 0.3048)
			(end -0.67945 0.3048)
			(stroke
				(width 0.1)
				(type default)
			)
			(layer "F.Fab")
		)
		(fp_line
			(start -0.12065 0.2794)
			(end -0.12065 0.3048)
			(stroke
				(width 0.1)
				(type default)
			)
			(layer "F.Fab")
		)
		(fp_line
			(start -0.12065 -0.2794)
			(end 0.12065 -0.2794)
			(stroke
				(width 0.1)
				(type default)
			)
			(layer "F.Fab")
		)
		(fp_line
			(start -0.12065 -0.305054)
			(end -0.12065 -0.2794)
			(stroke
				(width 0.1)
				(type default)
			)
			(layer "F.Fab")
		)
		(fp_line
			(start -0.67945 0.3048)
			(end -0.67945 -0.305054)
			(stroke
				(width 0.1)
				(type default)
			)
			(layer "F.Fab")
		)
		(fp_line
			(start -0.67945 -0.305054)
			(end -0.12065 -0.305054)
			(stroke
				(width 0.1)
				(type default)
			)
			(layer "F.Fab")
		)
		(pad "1" smd circle
			(at -0.40005 0 180)
			(size 0 0)
			(layers "F.Cu" "F.Mask" "F.Paste")
			(net "PVCCINFAON_CPU0_ATSEN")
		)
		(pad "2" smd circle
			(at 0.40005 0 180)
			(size 0 0)
			(layers "F.Cu" "F.Mask" "F.Paste")
			(net "GND")
		)
	)
	(footprint ""
		(layer "F.Cu")
		(at 449.52666 -51.976528)
		(property "Reference" "PC1866"
			(at 0 0 0)
			(layer "F.SilkS")
			(hide yes)
			(effects
				(font
					(size 1.27 1.27)
				)
			)
		)
		(property "Value" ""
			(at 0 0 0)
			(layer "F.Fab")
			(effects
				(font
					(size 1.27 1.27)
				)
			)
		)
		(duplicate_pad_numbers_are_jumpers no)
		(fp_line
			(start -3.400044 1.249934)
			(end 3.400044 1.249934)
			(stroke
				(width 0.1524)
				(type default)
			)
			(layer "F.SilkS")
		)
		(fp_circle
			(center 0 1.249934)
			(end 3.400044 1.249934)
			(stroke
				(width 0.1524)
				(type default)
			)
			(fill no)
			(layer "F.SilkS")
		)
		(fp_poly
			(pts
				(arc
					(start 3.400044 1.249934)
					(mid 0 4.649978)
					(end -3.400044 1.249934)
				)
			)
			(stroke
				(width 0)
				(type default)
			)
			(fill yes)
			(layer "F.SilkS")
		)
		(fp_circle
			(center 0 1.249934)
			(end 3.400044 1.249934)
			(stroke
				(width 0.1)
				(type default)
			)
			(fill no)
			(layer "F.Fab")
		)
		(pad "1" thru_hole rect
			(at 0 0)
			(size 1.524 1.524)
			(drill 1.016)
			(layers "*.Cu" "*.Mask")
			(remove_unused_layers no)
			(net "P3V3_AUX")
			(clearance 0)
			(padstack
				(mode front_inner_back)
				(layer "Inner"
					(shape circle)
					(size 1.524 1.524)
					(clearance 0)
				)
				(layer "B.Cu"
					(shape rect)
					(size 1.524 1.524)
					(clearance 0)
				)
			)
		)
		(pad "2" thru_hole circle
			(at 0 2.500122)
			(size 1.524 1.524)
			(drill 1.016)
			(layers "*.Cu" "*.Mask")
			(remove_unused_layers no)
			(net "GND")
			(clearance 0)
		)
	)
	(footprint ""
		(layer "F.Cu")
		(at 136.791954 -408.517344 -90)
		(property "Reference" "C1526"
			(at 0 0 270)
			(layer "F.SilkS")
			(hide yes)
			(effects
				(font
					(size 1.27 1.27)
				)
			)
		)
		(property "Value" ""
			(at 0 0 270)
			(layer "F.Fab")
			(effects
				(font
					(size 1.27 1.27)
				)
			)
		)
		(duplicate_pad_numbers_are_jumpers no)
		(fp_line
			(start -0.299974 0.150114)
			(end -0.299974 -0.150114)
			(stroke
				(width 0.1)
				(type default)
			)
			(layer "F.Fab")
		)
		(fp_line
			(start 0.299974 0.150114)
			(end -0.299974 0.150114)
			(stroke
				(width 0.1)
				(type default)
			)
			(layer "F.Fab")
		)
		(fp_line
			(start -0.299974 -0.150114)
			(end 0.299974 -0.150114)
			(stroke
				(width 0.1)
				(type default)
			)
			(layer "F.Fab")
		)
		(fp_line
			(start 0.299974 -0.150114)
			(end 0.299974 0.150114)
			(stroke
				(width 0.1)
				(type default)
			)
			(layer "F.Fab")
		)
		(pad "1" smd rect
			(at -0.2667 0 270)
			(size 0.3048 0.381)
			(layers "F.Cu" "F.Mask" "F.Paste")
			(net "P5E_CPU1_PE3_TX_C_DN<10>")
		)
		(pad "2" smd rect
			(at 0.2667 0 270)
			(size 0.3048 0.381)
			(layers "F.Cu" "F.Mask" "F.Paste")
			(net "P5E_CPU1_PE3_TX_DN<10>")
		)
	)
	(footprint ""
		(layer "F.Cu")
		(at 310.081168 -402.371052 -90)
		(property "Reference" "C1574"
			(at 0 0 270)
			(layer "F.SilkS")
			(hide yes)
			(effects
				(font
					(size 1.27 1.27)
				)
			)
		)
		(property "Value" ""
			(at 0 0 270)
			(layer "F.Fab")
			(effects
				(font
					(size 1.27 1.27)
				)
			)
		)
		(duplicate_pad_numbers_are_jumpers no)
		(fp_line
			(start -0.299974 0.150114)
			(end -0.299974 -0.150114)
			(stroke
				(width 0.1)
				(type default)
			)
			(layer "F.Fab")
		)
		(fp_line
			(start 0.299974 0.150114)
			(end -0.299974 0.150114)
			(stroke
				(width 0.1)
				(type default)
			)
			(layer "F.Fab")
		)
		(fp_line
			(start -0.299974 -0.150114)
			(end 0.299974 -0.150114)
			(stroke
				(width 0.1)
				(type default)
			)
			(layer "F.Fab")
		)
		(fp_line
			(start 0.299974 -0.150114)
			(end 0.299974 0.150114)
			(stroke
				(width 0.1)
				(type default)
			)
			(layer "F.Fab")
		)
		(pad "1" smd rect
			(at -0.2667 0 270)
			(size 0.3048 0.381)
			(layers "F.Cu" "F.Mask" "F.Paste")
			(net "P5E_CPU0_PE4_TX_C_DN<2>")
		)
		(pad "2" smd rect
			(at 0.2667 0 270)
			(size 0.3048 0.381)
			(layers "F.Cu" "F.Mask" "F.Paste")
			(net "P5E_CPU0_PE4_TX_DN<2>")
		)
	)
	(footprint ""
		(layer "F.Cu")
		(at 332.26756 -343.005156 -90)
		(property "Reference" "PC233_P0_7"
			(at 0 0 270)
			(layer "F.SilkS")
			(hide yes)
			(effects
				(font
					(size 1.27 1.27)
				)
			)
		)
		(property "Value" ""
			(at 0 0 270)
			(layer "F.Fab")
			(effects
				(font
					(size 1.27 1.27)
				)
			)
		)
		(duplicate_pad_numbers_are_jumpers no)
		(fp_line
			(start -0.7874 0.4064)
			(end -0.7874 -0.4064)
			(stroke
				(width 0.1524)
				(type default)
			)
			(layer "F.SilkS")
		)
		(fp_line
			(start 0.7874 0.4064)
			(end -0.7874 0.4064)
			(stroke
				(width 0.1524)
				(type default)
			)
			(layer "F.SilkS")
		)
		(fp_line
			(start -0.7874 -0.4064)
			(end 0.7874 -0.4064)
			(stroke
				(width 0.1524)
				(type default)
			)
			(layer "F.SilkS")
		)
		(fp_line
			(start 0.7874 -0.4064)
			(end 0.7874 0.4064)
			(stroke
				(width 0.1524)
				(type default)
			)
			(layer "F.SilkS")
		)
		(fp_line
			(start -0.67945 0.3048)
			(end -0.67945 -0.305054)
			(stroke
				(width 0.1)
				(type default)
			)
			(layer "F.Fab")
		)
		(fp_line
			(start -0.12065 0.3048)
			(end -0.67945 0.3048)
			(stroke
				(width 0.1)
				(type default)
			)
			(layer "F.Fab")
		)
		(fp_line
			(start 0.120396 0.3048)
			(end 0.120396 0.2794)
			(stroke
				(width 0.1)
				(type default)
			)
			(layer "F.Fab")
		)
		(fp_line
			(start 0.67945 0.3048)
			(end 0.120396 0.3048)
			(stroke
				(width 0.1)
				(type default)
			)
			(layer "F.Fab")
		)
		(fp_line
			(start -0.12065 0.2794)
			(end -0.12065 0.3048)
			(stroke
				(width 0.1)
				(type default)
			)
			(layer "F.Fab")
		)
		(fp_line
			(start 0.120396 0.2794)
			(end -0.12065 0.2794)
			(stroke
				(width 0.1)
				(type default)
			)
			(layer "F.Fab")
		)
		(fp_line
			(start -0.12065 -0.2794)
			(end 0.12065 -0.2794)
			(stroke
				(width 0.1)
				(type default)
			)
			(layer "F.Fab")
		)
		(fp_line
			(start 0.12065 -0.2794)
			(end 0.12065 -0.3048)
			(stroke
				(width 0.1)
				(type default)
			)
			(layer "F.Fab")
		)
		(fp_line
			(start 0.12065 -0.3048)
			(end 0.67945 -0.3048)
			(stroke
				(width 0.1)
				(type default)
			)
			(layer "F.Fab")
		)
		(fp_line
			(start 0.67945 -0.3048)
			(end 0.67945 0.3048)
			(stroke
				(width 0.1)
				(type default)
			)
			(layer "F.Fab")
		)
		(fp_line
			(start -0.67945 -0.305054)
			(end -0.12065 -0.305054)
			(stroke
				(width 0.1)
				(type default)
			)
			(layer "F.Fab")
		)
		(fp_line
			(start -0.12065 -0.305054)
			(end -0.12065 -0.2794)
			(stroke
				(width 0.1)
				(type default)
			)
			(layer "F.Fab")
		)
		(pad "1" smd circle
			(at -0.40005 0 270)
			(size 0 0)
			(layers "F.Cu" "F.Mask" "F.Paste")
			(net "SW_P12V_PVCCIN_CPU0_FLT")
		)
		(pad "2" smd circle
			(at 0.40005 0 270)
			(size 0 0)
			(layers "F.Cu" "F.Mask" "F.Paste")
			(net "GND")
		)
	)
	(footprint ""
		(layer "F.Cu")
		(at 332.115668 -76.153518 90)
		(property "Reference" "R4306"
			(at 0 0 90)
			(layer "F.SilkS")
			(hide yes)
			(effects
				(font
					(size 1.27 1.27)
				)
			)
		)
		(property "Value" ""
			(at 0 0 90)
			(layer "F.Fab")
			(effects
				(font
					(size 1.27 1.27)
				)
			)
		)
		(duplicate_pad_numbers_are_jumpers no)
		(fp_line
			(start 0.7874 -0.4064)
			(end 0.7874 0.4064)
			(stroke
				(width 0.1524)
				(type default)
			)
			(layer "F.SilkS")
		)
		(fp_line
			(start -0.7874 -0.4064)
			(end 0.7874 -0.4064)
			(stroke
				(width 0.1524)
				(type default)
			)
			(layer "F.SilkS")
		)
		(fp_line
			(start 0.7874 0.4064)
			(end -0.7874 0.4064)
			(stroke
				(width 0.1524)
				(type default)
			)
			(layer "F.SilkS")
		)
		(fp_line
			(start -0.7874 0.4064)
			(end -0.7874 -0.4064)
			(stroke
				(width 0.1524)
				(type default)
			)
			(layer "F.SilkS")
		)
		(fp_line
			(start -0.12065 -0.305054)
			(end -0.12065 -0.2794)
			(stroke
				(width 0.1)
				(type default)
			)
			(layer "F.Fab")
		)
		(fp_line
			(start -0.67945 -0.305054)
			(end -0.12065 -0.305054)
			(stroke
				(width 0.1)
				(type default)
			)
			(layer "F.Fab")
		)
		(fp_line
			(start 0.67945 -0.3048)
			(end 0.67945 0.3048)
			(stroke
				(width 0.1)
				(type default)
			)
			(layer "F.Fab")
		)
		(fp_line
			(start 0.12065 -0.3048)
			(end 0.67945 -0.3048)
			(stroke
				(width 0.1)
				(type default)
			)
			(layer "F.Fab")
		)
		(fp_line
			(start 0.12065 -0.2794)
			(end 0.12065 -0.3048)
			(stroke
				(width 0.1)
				(type default)
			)
			(layer "F.Fab")
		)
		(fp_line
			(start -0.12065 -0.2794)
			(end 0.12065 -0.2794)
			(stroke
				(width 0.1)
				(type default)
			)
			(layer "F.Fab")
		)
		(fp_line
			(start 0.120396 0.2794)
			(end -0.12065 0.2794)
			(stroke
				(width 0.1)
				(type default)
			)
			(layer "F.Fab")
		)
		(fp_line
			(start -0.12065 0.2794)
			(end -0.12065 0.3048)
			(stroke
				(width 0.1)
				(type default)
			)
			(layer "F.Fab")
		)
		(fp_line
			(start 0.67945 0.3048)
			(end 0.120396 0.3048)
			(stroke
				(width 0.1)
				(type default)
			)
			(layer "F.Fab")
		)
		(fp_line
			(start 0.120396 0.3048)
			(end 0.120396 0.2794)
			(stroke
				(width 0.1)
				(type default)
			)
			(layer "F.Fab")
		)
		(fp_line
			(start -0.12065 0.3048)
			(end -0.67945 0.3048)
			(stroke
				(width 0.1)
				(type default)
			)
			(layer "F.Fab")
		)
		(fp_line
			(start -0.67945 0.3048)
			(end -0.67945 -0.305054)
			(stroke
				(width 0.1)
				(type default)
			)
			(layer "F.Fab")
		)
		(pad "1" smd circle
			(at -0.40005 0 90)
			(size 0 0)
			(layers "F.Cu" "F.Mask" "F.Paste")
			(net "CLK_100M_PE_M2_0_R_DN")
		)
		(pad "2" smd circle
			(at 0.40005 0 90)
			(size 0 0)
			(layers "F.Cu" "F.Mask" "F.Paste")
			(net "CLK_100M_PE_M2_0_DN")
		)
	)
	(footprint ""
		(layer "F.Cu")
		(at 163.50615 -430.706276)
		(property "Reference" "R2705"
			(at 0 0 0)
			(layer "F.SilkS")
			(hide yes)
			(effects
				(font
					(size 1.27 1.27)
				)
			)
		)
		(property "Value" ""
			(at 0 0 0)
			(layer "F.Fab")
			(effects
				(font
					(size 1.27 1.27)
				)
			)
		)
		(duplicate_pad_numbers_are_jumpers no)
		(fp_line
			(start -0.7874 -0.4064)
			(end 0.7874 -0.4064)
			(stroke
				(width 0.1524)
				(type default)
			)
			(layer "F.SilkS")
		)
		(fp_line
			(start -0.7874 0.4064)
			(end -0.7874 -0.4064)
			(stroke
				(width 0.1524)
				(type default)
			)
			(layer "F.SilkS")
		)
		(fp_line
			(start 0.7874 -0.4064)
			(end 0.7874 0.4064)
			(stroke
				(width 0.1524)
				(type default)
			)
			(layer "F.SilkS")
		)
		(fp_line
			(start 0.7874 0.4064)
			(end -0.7874 0.4064)
			(stroke
				(width 0.1524)
				(type default)
			)
			(layer "F.SilkS")
		)
		(fp_line
			(start -0.67945 -0.305054)
			(end -0.12065 -0.305054)
			(stroke
				(width 0.1)
				(type default)
			)
			(layer "F.Fab")
		)
		(fp_line
			(start -0.67945 0.3048)
			(end -0.67945 -0.305054)
			(stroke
				(width 0.1)
				(type default)
			)
			(layer "F.Fab")
		)
		(fp_line
			(start -0.12065 -0.305054)
			(end -0.12065 -0.2794)
			(stroke
				(width 0.1)
				(type default)
			)
			(layer "F.Fab")
		)
		(fp_line
			(start -0.12065 -0.2794)
			(end 0.12065 -0.2794)
			(stroke
				(width 0.1)
				(type default)
			)
			(layer "F.Fab")
		)
		(fp_line
			(start -0.12065 0.2794)
			(end -0.12065 0.3048)
			(stroke
				(width 0.1)
				(type default)
			)
			(layer "F.Fab")
		)
		(fp_line
			(start -0.12065 0.3048)
			(end -0.67945 0.3048)
			(stroke
				(width 0.1)
				(type default)
			)
			(layer "F.Fab")
		)
		(fp_line
			(start 0.120396 0.2794)
			(end -0.12065 0.2794)
			(stroke
				(width 0.1)
				(type default)
			)
			(layer "F.Fab")
		)
		(fp_line
			(start 0.120396 0.3048)
			(end 0.120396 0.2794)
			(stroke
				(width 0.1)
				(type default)
			)
			(layer "F.Fab")
		)
		(fp_line
			(start 0.12065 -0.3048)
			(end 0.67945 -0.3048)
			(stroke
				(width 0.1)
				(type default)
			)
			(layer "F.Fab")
		)
		(fp_line
			(start 0.12065 -0.2794)
			(end 0.12065 -0.3048)
			(stroke
				(width 0.1)
				(type default)
			)
			(layer "F.Fab")
		)
		(fp_line
			(start 0.67945 -0.3048)
			(end 0.67945 0.3048)
			(stroke
				(width 0.1)
				(type default)
			)
			(layer "F.Fab")
		)
		(fp_line
			(start 0.67945 0.3048)
			(end 0.120396 0.3048)
			(stroke
				(width 0.1)
				(type default)
			)
			(layer "F.Fab")
		)
		(pad "1" smd circle
			(at -0.40005 0)
			(size 0 0)
			(layers "F.Cu" "F.Mask" "F.Paste")
			(net "SMB_BMC_SWB_R_SCL")
		)
		(pad "2" smd circle
			(at 0.40005 0)
			(size 0 0)
			(layers "F.Cu" "F.Mask" "F.Paste")
			(net "SMB_BMC_SWB_BUF_R_SCL")
		)
	)
)
